(kicad_pcb
	(version 20260206)
	(generator "pcbnew")
	(generator_version "10.0")
	(general
		(thickness 1.6)
		(legacy_teardrops no)
	)
	(paper "A4")
	(title_block
		(title "panther-plus-userver — 13130-1b_20150205.brd")
		(comment 1 "Honey Badger (Wiwynn) / footprint 406 of 1509 (DIMM2), pads 72-78 of 210")
	)
	(layers
		(0 "F.Cu" signal "TOP")
		(4 "In1.Cu" signal "L2")
		(6 "In2.Cu" signal "L3")
		(8 "In3.Cu" signal "L4")
		(10 "In4.Cu" signal "L5")
		(12 "In5.Cu" signal "L6")
		(14 "In6.Cu" signal "L7")
		(16 "In7.Cu" signal "L8")
		(18 "In8.Cu" signal "L9")
		(20 "In9.Cu" signal "L10")
		(22 "In10.Cu" signal "L11")
		(2 "B.Cu" signal "BOTTOM")
		(9 "F.Adhes" user "F.Adhesive")
		(11 "B.Adhes" user "B.Adhesive")
		(13 "F.Paste" user "Package Geometry/Pastemask Top")
		(15 "B.Paste" user "Package Geometry/Pastemask Bottom")
		(5 "F.SilkS" user "Ref Des/Silkscreen Top")
		(7 "B.SilkS" user "Ref Des/Silkscreen Bottom")
		(1 "F.Mask" user "Board Geometry/Soldermask Top")
		(3 "B.Mask" user "Board Geometry/Soldermask Bottom")
		(17 "Dwgs.User" user "User.Drawings")
		(19 "Cmts.User" user "User.Comments")
		(21 "Eco1.User" user "User.Eco1")
		(23 "Eco2.User" user "User.Eco2")
		(25 "Edge.Cuts" user "Board Geometry/Outline")
		(27 "Margin" user)
		(31 "F.CrtYd" user "Package Geometry/Place Bound Top")
		(29 "B.CrtYd" user "Package Geometry/Place Bound Bottom")
		(35 "F.Fab" user "Ref Des/Assembly Top")
		(33 "B.Fab" user "Ref Des/Assembly Bottom")
	)
	(footprint ""
		(layer "F.Cu")
		(at 158.500064 -66.699892 180)
		(property "Reference" "DIMM2"
			(at 0 0 180)
			(layer "F.SilkS")
			(hide yes)
			(effects
				(font
					(size 1.27 1.27)
				)
			)
		)
		(property "Value" "DDR3-204P-174-COLAY-1-GP"
			(at -40.682164 -17.468088 180)
			(unlocked yes)
			(layer "F.Fab")
			(hide yes)
			(effects
				(font
					(size 1.016 1.016)
					(thickness 0.1524)
				)
			)
		)
		(property "Device Type" "AS0A626-H8SN-7H-COLAY-1"
			(at -40.682164 -18.992088 180)
			(unlocked yes)
			(layer "F.Fab")
			(hide yes)
			(effects
				(font
					(size 1.016 1.016)
					(thickness 0.1524)
				)
			)
		)
		(duplicate_pad_numbers_are_jumpers no)
		(pad "70" smd custom
			(at -10.94994 -4.106672 180)
			(size 0.1143 0.1143)
			(layers "F.Cu" "F.Mask" "F.Paste")
			(net "GND")
			(options
				(clearance outline)
				(anchor circle)
			)
			(primitives
				(gr_poly
					(pts
						(xy 0 0.9017) (xy -0.03175 0.89916) (xy -0.0635 0.889) (xy -0.09144 0.87376) (xy -0.11684 0.85344)
						(xy -0.13716 0.82804) (xy -0.1524 0.8001) (xy -0.16256 0.76835) (xy -0.1651 0.7366) (xy -0.1651 0.44958)
						(xy -0.17272 0.44196) (xy -0.19812 0.4064) (xy -0.2032 0.39624) (xy -0.20701 0.38735) (xy -0.21209 0.37719)
						(xy -0.2159 0.36703) (xy -0.21844 0.35687) (xy -0.22225 0.34544) (xy -0.22352 0.33528) (xy -0.22606 0.32512)
						(xy -0.22733 0.31369) (xy -0.22733 0.30353) (xy -0.2286 0.2921) (xy -0.22733 0.28067) (xy -0.22733 0.27051)
						(xy -0.22606 0.25908) (xy -0.22352 0.24892) (xy -0.22225 0.23876) (xy -0.21844 0.22733) (xy -0.2159 0.21717)
						(xy -0.21209 0.20701) (xy -0.20701 0.19685) (xy -0.2032 0.18796) (xy -0.19812 0.1778) (xy -0.17272 0.14224)
						(xy -0.1651 0.13462) (xy -0.1651 -0.7366) (xy -0.16256 -0.76835) (xy -0.1524 -0.8001) (xy -0.13716 -0.82804)
						(xy -0.11684 -0.85344) (xy -0.09144 -0.87376) (xy -0.0635 -0.889) (xy -0.03175 -0.89916) (xy 0 -0.9017)
						(xy 0.03175 -0.89916) (xy 0.0635 -0.889) (xy 0.09144 -0.87376) (xy 0.11684 -0.85344) (xy 0.13716 -0.82804)
						(xy 0.1524 -0.8001) (xy 0.16256 -0.76835) (xy 0.1651 -0.7366) (xy 0.1651 0.13462) (xy 0.17272 0.14224)
						(xy 0.19812 0.1778) (xy 0.2032 0.18796) (xy 0.20701 0.19685) (xy 0.21209 0.20701) (xy 0.2159 0.21717)
						(xy 0.21844 0.22733) (xy 0.22225 0.23876) (xy 0.22352 0.24892) (xy 0.22606 0.25908) (xy 0.22733 0.27051)
						(xy 0.22733 0.28067) (xy 0.2286 0.2921) (xy 0.22733 0.30353) (xy 0.22733 0.31369) (xy 0.22606 0.32512)
						(xy 0.22352 0.33528) (xy 0.22225 0.34544) (xy 0.21844 0.35687) (xy 0.2159 0.36703) (xy 0.21209 0.37719)
						(xy 0.20701 0.38735) (xy 0.2032 0.39624) (xy 0.19812 0.4064) (xy 0.17272 0.44196) (xy 0.1651 0.44958)
						(xy 0.1651 0.7366) (xy 0.16256 0.76835) (xy 0.1524 0.8001) (xy 0.13716 0.82804) (xy 0.11684 0.85344)
						(xy 0.09144 0.87376) (xy 0.0635 0.889) (xy 0.03175 0.89916)
					)
					(width 0)
					(fill yes)
				)
			)
		)
		(pad "71" smd custom
			(at -10.649966 4.106672 180)
			(size 0.1143 0.1143)
			(layers "F.Cu" "F.Mask" "F.Paste")
			(net "M_A_ECC5")
			(options
				(clearance outline)
				(anchor circle)
			)
			(primitives
				(gr_poly
					(pts
						(xy 0 0.9017) (xy -0.03175 0.89916) (xy -0.0635 0.889) (xy -0.09144 0.87376) (xy -0.11684 0.85344)
						(xy -0.13716 0.82804) (xy -0.1524 0.8001) (xy -0.16256 0.76835) (xy -0.1651 0.7366) (xy -0.1651 0.11938)
						(xy -0.17272 0.11176) (xy -0.19812 0.0762) (xy -0.2032 0.06604) (xy -0.20701 0.05715) (xy -0.21209 0.04699)
						(xy -0.2159 0.03683) (xy -0.21844 0.02667) (xy -0.22225 0.01524) (xy -0.22352 0.00508) (xy -0.22606 -0.00508)
						(xy -0.22733 -0.01651) (xy -0.22733 -0.02667) (xy -0.2286 -0.0381) (xy -0.22733 -0.04953) (xy -0.22733 -0.05969)
						(xy -0.22606 -0.07112) (xy -0.22352 -0.08128) (xy -0.22225 -0.09144) (xy -0.21844 -0.10287) (xy -0.2159 -0.11303)
						(xy -0.21209 -0.12319) (xy -0.20701 -0.13335) (xy -0.2032 -0.14224) (xy -0.19812 -0.1524) (xy -0.17272 -0.18796)
						(xy -0.1651 -0.19558) (xy -0.1651 -0.7366) (xy -0.16256 -0.76835) (xy -0.1524 -0.8001) (xy -0.13716 -0.82804)
						(xy -0.11684 -0.85344) (xy -0.09144 -0.87376) (xy -0.0635 -0.889) (xy -0.03175 -0.89916) (xy 0 -0.9017)
						(xy 0.03175 -0.89916) (xy 0.0635 -0.889) (xy 0.09144 -0.87376) (xy 0.11684 -0.85344) (xy 0.13716 -0.82804)
						(xy 0.1524 -0.8001) (xy 0.16256 -0.76835) (xy 0.1651 -0.7366) (xy 0.1651 -0.19685) (xy 0.17272 -0.18923)
						(xy 0.17907 -0.18034) (xy 0.18669 -0.17145) (xy 0.19177 -0.16256) (xy 0.19812 -0.15367) (xy 0.20828 -0.13335)
						(xy 0.21971 -0.10287) (xy 0.22225 -0.09271) (xy 0.22479 -0.08128) (xy 0.22606 -0.07112) (xy 0.2286 -0.05969)
						(xy 0.2286 -0.01651) (xy 0.22606 -0.00508) (xy 0.22479 0.00508) (xy 0.22225 0.01651) (xy 0.21971 0.02667)
						(xy 0.20828 0.05715) (xy 0.19812 0.07747) (xy 0.19177 0.08636) (xy 0.18669 0.09525) (xy 0.17907 0.10414)
						(xy 0.17272 0.11303) (xy 0.1651 0.12065) (xy 0.1651 0.7366) (xy 0.16256 0.76835) (xy 0.1524 0.8001)
						(xy 0.13716 0.82804) (xy 0.11684 0.85344) (xy 0.09144 0.87376) (xy 0.0635 0.889) (xy 0.03175 0.89916)
					)
					(width 0)
					(fill yes)
				)
			)
		)
		(pad "72" smd custom
			(at -10.349992 -4.106672 180)
			(size 0.1143 0.1143)
			(layers "F.Cu" "F.Mask" "F.Paste")
			(net "M_A_ECC0")
			(options
				(clearance outline)
				(anchor circle)
			)
			(primitives
				(gr_poly
					(pts
						(xy 0 0.9017) (xy -0.03175 0.89916) (xy -0.0635 0.889) (xy -0.09144 0.87376) (xy -0.11684 0.85344)
						(xy -0.13716 0.82804) (xy -0.1524 0.8001) (xy -0.16256 0.76835) (xy -0.1651 0.7366) (xy -0.1651 0.19685)
						(xy -0.17272 0.18923) (xy -0.17907 0.18034) (xy -0.18669 0.17145) (xy -0.19177 0.16256) (xy -0.19812 0.15367)
						(xy -0.20828 0.13335) (xy -0.21971 0.10287) (xy -0.22225 0.09271) (xy -0.22479 0.08128) (xy -0.22606 0.07112)
						(xy -0.2286 0.05969) (xy -0.2286 0.01651) (xy -0.22606 0.00508) (xy -0.22479 -0.00508) (xy -0.22225 -0.01651)
						(xy -0.21971 -0.02667) (xy -0.20828 -0.05715) (xy -0.19812 -0.07747) (xy -0.19177 -0.08636) (xy -0.18669 -0.09525)
						(xy -0.17907 -0.10414) (xy -0.17272 -0.11303) (xy -0.1651 -0.12065) (xy -0.1651 -0.7366) (xy -0.16256 -0.76835)
						(xy -0.1524 -0.8001) (xy -0.13716 -0.82804) (xy -0.11684 -0.85344) (xy -0.09144 -0.87376) (xy -0.0635 -0.889)
						(xy -0.03175 -0.89916) (xy 0 -0.9017) (xy 0.03175 -0.89916) (xy 0.0635 -0.889) (xy 0.09144 -0.87376)
						(xy 0.11684 -0.85344) (xy 0.13716 -0.82804) (xy 0.1524 -0.8001) (xy 0.16256 -0.76835) (xy 0.1651 -0.7366)
						(xy 0.1651 -0.11938) (xy 0.17272 -0.11176) (xy 0.19812 -0.0762) (xy 0.2032 -0.06604) (xy 0.20701 -0.05715)
						(xy 0.21209 -0.04699) (xy 0.2159 -0.03683) (xy 0.21844 -0.02667) (xy 0.22225 -0.01524) (xy 0.22352 -0.00508)
						(xy 0.22606 0.00508) (xy 0.22733 0.01651) (xy 0.22733 0.02667) (xy 0.2286 0.0381) (xy 0.22733 0.04953)
						(xy 0.22733 0.05969) (xy 0.22606 0.07112) (xy 0.22352 0.08128) (xy 0.22225 0.09144) (xy 0.21844 0.10287)
						(xy 0.2159 0.11303) (xy 0.21209 0.12319) (xy 0.20701 0.13335) (xy 0.2032 0.14224) (xy 0.19812 0.1524)
						(xy 0.17272 0.18796) (xy 0.1651 0.19558) (xy 0.1651 0.7366) (xy 0.16256 0.76835) (xy 0.1524 0.8001)
						(xy 0.13716 0.82804) (xy 0.11684 0.85344) (xy 0.09144 0.87376) (xy 0.0635 0.889) (xy 0.03175 0.89916)
					)
					(width 0)
					(fill yes)
				)
			)
		)
		(pad "73" smd custom
			(at -7.649972 4.106672 180)
			(size 0.1143 0.1143)
			(layers "F.Cu" "F.Mask" "F.Paste")
			(net "GND")
			(options
				(clearance outline)
				(anchor circle)
			)
			(primitives
				(gr_poly
					(pts
						(xy 0 0.9017) (xy -0.03175 0.89916) (xy -0.0635 0.889) (xy -0.09144 0.87376) (xy -0.11684 0.85344)
						(xy -0.13716 0.82804) (xy -0.1524 0.8001) (xy -0.16256 0.76835) (xy -0.1651 0.7366) (xy -0.1651 -0.13462)
						(xy -0.17272 -0.14224) (xy -0.19812 -0.1778) (xy -0.2032 -0.18796) (xy -0.20701 -0.19685) (xy -0.21209 -0.20701)
						(xy -0.2159 -0.21717) (xy -0.21844 -0.22733) (xy -0.22225 -0.23876) (xy -0.22352 -0.24892) (xy -0.22606 -0.25908)
						(xy -0.22733 -0.27051) (xy -0.22733 -0.28067) (xy -0.2286 -0.2921) (xy -0.22733 -0.30353) (xy -0.22733 -0.31369)
						(xy -0.22606 -0.32512) (xy -0.22352 -0.33528) (xy -0.22225 -0.34544) (xy -0.21844 -0.35687) (xy -0.2159 -0.36703)
						(xy -0.21209 -0.37719) (xy -0.20701 -0.38735) (xy -0.2032 -0.39624) (xy -0.19812 -0.4064) (xy -0.17272 -0.44196)
						(xy -0.1651 -0.44958) (xy -0.1651 -0.7366) (xy -0.16256 -0.76835) (xy -0.1524 -0.8001) (xy -0.13716 -0.82804)
						(xy -0.11684 -0.85344) (xy -0.09144 -0.87376) (xy -0.0635 -0.889) (xy -0.03175 -0.89916) (xy 0 -0.9017)
						(xy 0.03175 -0.89916) (xy 0.0635 -0.889) (xy 0.09144 -0.87376) (xy 0.11684 -0.85344) (xy 0.13716 -0.82804)
						(xy 0.1524 -0.8001) (xy 0.16256 -0.76835) (xy 0.1651 -0.7366) (xy 0.1651 -0.44958) (xy 0.17272 -0.44196)
						(xy 0.19812 -0.4064) (xy 0.2032 -0.39624) (xy 0.20701 -0.38735) (xy 0.21209 -0.37719) (xy 0.2159 -0.36703)
						(xy 0.21844 -0.35687) (xy 0.22225 -0.34544) (xy 0.22352 -0.33528) (xy 0.22606 -0.32512) (xy 0.22733 -0.31369)
						(xy 0.22733 -0.30353) (xy 0.2286 -0.2921) (xy 0.22733 -0.28067) (xy 0.22733 -0.27051) (xy 0.22606 -0.25908)
						(xy 0.22352 -0.24892) (xy 0.22225 -0.23876) (xy 0.21844 -0.22733) (xy 0.2159 -0.21717) (xy 0.21209 -0.20701)
						(xy 0.20701 -0.19685) (xy 0.2032 -0.18796) (xy 0.19812 -0.1778) (xy 0.17272 -0.14224) (xy 0.1651 -0.13462)
						(xy 0.1651 0.7366) (xy 0.16256 0.76835) (xy 0.1524 0.8001) (xy 0.13716 0.82804) (xy 0.11684 0.85344)
						(xy 0.09144 0.87376) (xy 0.0635 0.889) (xy 0.03175 0.89916)
					)
					(width 0)
					(fill yes)
				)
			)
		)
		(pad "74" smd custom
			(at -7.349998 -4.106672 180)
			(size 0.1143 0.1143)
			(layers "F.Cu" "F.Mask" "F.Paste")
			(net "M_A_ECC1")
			(options
				(clearance outline)
				(anchor circle)
			)
			(primitives
				(gr_poly
					(pts
						(xy 0 0.9017) (xy -0.03175 0.89916) (xy -0.0635 0.889) (xy -0.09144 0.87376) (xy -0.11684 0.85344)
						(xy -0.13716 0.82804) (xy -0.1524 0.8001) (xy -0.16256 0.76835) (xy -0.1651 0.7366) (xy -0.1651 0.44958)
						(xy -0.17272 0.44196) (xy -0.19812 0.4064) (xy -0.2032 0.39624) (xy -0.20701 0.38735) (xy -0.21209 0.37719)
						(xy -0.2159 0.36703) (xy -0.21844 0.35687) (xy -0.22225 0.34544) (xy -0.22352 0.33528) (xy -0.22606 0.32512)
						(xy -0.22733 0.31369) (xy -0.22733 0.30353) (xy -0.2286 0.2921) (xy -0.22733 0.28067) (xy -0.22733 0.27051)
						(xy -0.22606 0.25908) (xy -0.22352 0.24892) (xy -0.22225 0.23876) (xy -0.21844 0.22733) (xy -0.2159 0.21717)
						(xy -0.21209 0.20701) (xy -0.20701 0.19685) (xy -0.2032 0.18796) (xy -0.19812 0.1778) (xy -0.17272 0.14224)
						(xy -0.1651 0.13462) (xy -0.1651 -0.7366) (xy -0.16256 -0.76835) (xy -0.1524 -0.8001) (xy -0.13716 -0.82804)
						(xy -0.11684 -0.85344) (xy -0.09144 -0.87376) (xy -0.0635 -0.889) (xy -0.03175 -0.89916) (xy 0 -0.9017)
						(xy 0.03175 -0.89916) (xy 0.0635 -0.889) (xy 0.09144 -0.87376) (xy 0.11684 -0.85344) (xy 0.13716 -0.82804)
						(xy 0.1524 -0.8001) (xy 0.16256 -0.76835) (xy 0.1651 -0.7366) (xy 0.1651 0.13462) (xy 0.17272 0.14224)
						(xy 0.19812 0.1778) (xy 0.2032 0.18796) (xy 0.20701 0.19685) (xy 0.21209 0.20701) (xy 0.2159 0.21717)
						(xy 0.21844 0.22733) (xy 0.22225 0.23876) (xy 0.22352 0.24892) (xy 0.22606 0.25908) (xy 0.22733 0.27051)
						(xy 0.22733 0.28067) (xy 0.2286 0.2921) (xy 0.22733 0.30353) (xy 0.22733 0.31369) (xy 0.22606 0.32512)
						(xy 0.22352 0.33528) (xy 0.22225 0.34544) (xy 0.21844 0.35687) (xy 0.2159 0.36703) (xy 0.21209 0.37719)
						(xy 0.20701 0.38735) (xy 0.2032 0.39624) (xy 0.19812 0.4064) (xy 0.17272 0.44196) (xy 0.1651 0.44958)
						(xy 0.1651 0.7366) (xy 0.16256 0.76835) (xy 0.1524 0.8001) (xy 0.13716 0.82804) (xy 0.11684 0.85344)
						(xy 0.09144 0.87376) (xy 0.0635 0.889) (xy 0.03175 0.89916)
					)
					(width 0)
					(fill yes)
				)
			)
		)
		(pad "75" smd custom
			(at -7.050024 4.106672 180)
			(size 0.1143 0.1143)
			(layers "F.Cu" "F.Mask" "F.Paste")
			(net "M_A_DQS_DN8")
			(options
				(clearance outline)
				(anchor circle)
			)
			(primitives
				(gr_poly
					(pts
						(xy 0 0.9017) (xy -0.03175 0.89916) (xy -0.0635 0.889) (xy -0.09144 0.87376) (xy -0.11684 0.85344)
						(xy -0.13716 0.82804) (xy -0.1524 0.8001) (xy -0.16256 0.76835) (xy -0.1651 0.7366) (xy -0.1651 0.11938)
						(xy -0.17272 0.11176) (xy -0.19812 0.0762) (xy -0.2032 0.06604) (xy -0.20701 0.05715) (xy -0.21209 0.04699)
						(xy -0.2159 0.03683) (xy -0.21844 0.02667) (xy -0.22225 0.01524) (xy -0.22352 0.00508) (xy -0.22606 -0.00508)
						(xy -0.22733 -0.01651) (xy -0.22733 -0.02667) (xy -0.2286 -0.0381) (xy -0.22733 -0.04953) (xy -0.22733 -0.05969)
						(xy -0.22606 -0.07112) (xy -0.22352 -0.08128) (xy -0.22225 -0.09144) (xy -0.21844 -0.10287) (xy -0.2159 -0.11303)
						(xy -0.21209 -0.12319) (xy -0.20701 -0.13335) (xy -0.2032 -0.14224) (xy -0.19812 -0.1524) (xy -0.17272 -0.18796)
						(xy -0.1651 -0.19558) (xy -0.1651 -0.7366) (xy -0.16256 -0.76835) (xy -0.1524 -0.8001) (xy -0.13716 -0.82804)
						(xy -0.11684 -0.85344) (xy -0.09144 -0.87376) (xy -0.0635 -0.889) (xy -0.03175 -0.89916) (xy 0 -0.9017)
						(xy 0.03175 -0.89916) (xy 0.0635 -0.889) (xy 0.09144 -0.87376) (xy 0.11684 -0.85344) (xy 0.13716 -0.82804)
						(xy 0.1524 -0.8001) (xy 0.16256 -0.76835) (xy 0.1651 -0.7366) (xy 0.1651 -0.19685) (xy 0.17272 -0.18923)
						(xy 0.17907 -0.18034) (xy 0.18669 -0.17145) (xy 0.19177 -0.16256) (xy 0.19812 -0.15367) (xy 0.20828 -0.13335)
						(xy 0.21971 -0.10287) (xy 0.22225 -0.09271) (xy 0.22479 -0.08128) (xy 0.22606 -0.07112) (xy 0.2286 -0.05969)
						(xy 0.2286 -0.01651) (xy 0.22606 -0.00508) (xy 0.22479 0.00508) (xy 0.22225 0.01651) (xy 0.21971 0.02667)
						(xy 0.20828 0.05715) (xy 0.19812 0.07747) (xy 0.19177 0.08636) (xy 0.18669 0.09525) (xy 0.17907 0.10414)
						(xy 0.17272 0.11303) (xy 0.1651 0.12065) (xy 0.1651 0.7366) (xy 0.16256 0.76835) (xy 0.1524 0.8001)
						(xy 0.13716 0.82804) (xy 0.11684 0.85344) (xy 0.09144 0.87376) (xy 0.0635 0.889) (xy 0.03175 0.89916)
					)
					(width 0)
					(fill yes)
				)
			)
		)
		(pad "76" smd custom
			(at -6.75005 -4.106672 180)
			(size 0.1143 0.1143)
			(layers "F.Cu" "F.Mask" "F.Paste")
			(net "GND")
			(options
				(clearance outline)
				(anchor circle)
			)
			(primitives
				(gr_poly
					(pts
						(xy 0 0.9017) (xy -0.03175 0.89916) (xy -0.0635 0.889) (xy -0.09144 0.87376) (xy -0.11684 0.85344)
						(xy -0.13716 0.82804) (xy -0.1524 0.8001) (xy -0.16256 0.76835) (xy -0.1651 0.7366) (xy -0.1651 0.19685)
						(xy -0.17272 0.18923) (xy -0.17907 0.18034) (xy -0.18669 0.17145) (xy -0.19177 0.16256) (xy -0.19812 0.15367)
						(xy -0.20828 0.13335) (xy -0.21971 0.10287) (xy -0.22225 0.09271) (xy -0.22479 0.08128) (xy -0.22606 0.07112)
						(xy -0.2286 0.05969) (xy -0.2286 0.01651) (xy -0.22606 0.00508) (xy -0.22479 -0.00508) (xy -0.22225 -0.01651)
						(xy -0.21971 -0.02667) (xy -0.20828 -0.05715) (xy -0.19812 -0.07747) (xy -0.19177 -0.08636) (xy -0.18669 -0.09525)
						(xy -0.17907 -0.10414) (xy -0.17272 -0.11303) (xy -0.1651 -0.12065) (xy -0.1651 -0.7366) (xy -0.16256 -0.76835)
						(xy -0.1524 -0.8001) (xy -0.13716 -0.82804) (xy -0.11684 -0.85344) (xy -0.09144 -0.87376) (xy -0.0635 -0.889)
						(xy -0.03175 -0.89916) (xy 0 -0.9017) (xy 0.03175 -0.89916) (xy 0.0635 -0.889) (xy 0.09144 -0.87376)
						(xy 0.11684 -0.85344) (xy 0.13716 -0.82804) (xy 0.1524 -0.8001) (xy 0.16256 -0.76835) (xy 0.1651 -0.7366)
						(xy 0.1651 -0.11938) (xy 0.17272 -0.11176) (xy 0.19812 -0.0762) (xy 0.2032 -0.06604) (xy 0.20701 -0.05715)
						(xy 0.21209 -0.04699) (xy 0.2159 -0.03683) (xy 0.21844 -0.02667) (xy 0.22225 -0.01524) (xy 0.22352 -0.00508)
						(xy 0.22606 0.00508) (xy 0.22733 0.01651) (xy 0.22733 0.02667) (xy 0.2286 0.0381) (xy 0.22733 0.04953)
						(xy 0.22733 0.05969) (xy 0.22606 0.07112) (xy 0.22352 0.08128) (xy 0.22225 0.09144) (xy 0.21844 0.10287)
						(xy 0.2159 0.11303) (xy 0.21209 0.12319) (xy 0.20701 0.13335) (xy 0.2032 0.14224) (xy 0.19812 0.1524)
						(xy 0.17272 0.18796) (xy 0.1651 0.19558) (xy 0.1651 0.7366) (xy 0.16256 0.76835) (xy 0.1524 0.8001)
						(xy 0.13716 0.82804) (xy 0.11684 0.85344) (xy 0.09144 0.87376) (xy 0.0635 0.889) (xy 0.03175 0.89916)
					)
					(width 0)
					(fill yes)
				)
			)
		)
	)
)
